(kicad_pcb
	(version 20260206)
	(generator "pcbnew")
	(generator_version "10.0")
	(general
		(thickness 1.6)
		(legacy_teardrops no)
	)
	(paper "A4")
	(title_block
		(title "Bryce Canyon_IOM_IOC_16318-2_OCP.brd")
		(comment 1 "Bryce Canyon / footprints 1256-1263 of 1605")
	)
	(layers
		(0 "F.Cu" signal "TOP")
		(4 "In1.Cu" signal "L2GND")
		(6 "In2.Cu" signal "L3")
		(8 "In3.Cu" signal "L4VCC")
		(10 "In4.Cu" signal "L5VCC")
		(12 "In5.Cu" signal "L6")
		(14 "In6.Cu" signal "L7GND")
		(2 "B.Cu" signal "BOTTOM")
		(9 "F.Adhes" user "F.Adhesive")
		(11 "B.Adhes" user "B.Adhesive")
		(13 "F.Paste" user "Package Geometry/Pastemask Top")
		(15 "B.Paste" user "Package Geometry/Pastemask Bottom")
		(5 "F.SilkS" user "Ref Des/Silkscreen Top")
		(7 "B.SilkS" user "Ref Des/Silkscreen Bottom")
		(1 "F.Mask" user "Board Geometry/Soldermask Top")
		(3 "B.Mask" user "Board Geometry/Soldermask Bottom")
		(17 "Dwgs.User" user "User.Drawings")
		(19 "Cmts.User" user "User.Comments")
		(21 "Eco1.User" user "User.Eco1")
		(23 "Eco2.User" user "User.Eco2")
		(25 "Edge.Cuts" user "Board Geometry/Outline")
		(27 "Margin" user)
		(31 "F.CrtYd" user "Package Geometry/Place Bound Top")
		(29 "B.CrtYd" user "Package Geometry/Place Bound Bottom")
		(35 "F.Fab" user "Ref Des/Assembly Top")
		(33 "B.Fab" user "Ref Des/Assembly Bottom")
	)
	(footprint ""
		(layer "B.Cu")
		(at 181.6608 -76.2 -90)
		(property "Reference" "TP95"
			(at 0 0 90)
			(layer "B.SilkS")
			(hide yes)
			(effects
				(font
					(size 1.27 1.27)
				)
				(justify mirror)
			)
		)
		(property "Value" "TPAD28-2-GP"
			(at 0.0127 -1.6637 270)
			(unlocked yes)
			(layer "B.Fab")
			(hide yes)
			(effects
				(font
					(size 1.016 1.016)
					(thickness 0.1524)
				)
				(justify mirror)
			)
		)
		(property "Device Type" "TPAD28"
			(at 0.0127 -3.1877 270)
			(unlocked yes)
			(layer "B.Fab")
			(hide yes)
			(effects
				(font
					(size 1.016 1.016)
					(thickness 0.1524)
				)
				(justify mirror)
			)
		)
		(duplicate_pad_numbers_are_jumpers no)
		(fp_poly
			(pts
				(arc
					(start 0 -0.3556)
					(mid 0 0.3556)
					(end 0 -0.3556)
				)
			)
			(stroke
				(width 0)
				(type default)
			)
			(fill no)
			(layer "B.CrtYd")
		)
		(fp_poly
			(pts
				(arc
					(start 0 -0.6096)
					(mid 0 0.6096)
					(end 0 -0.6096)
				)
			)
			(stroke
				(width 0)
				(type default)
			)
			(fill no)
			(layer "B.Fab")
		)
		(pad "1" smd circle
			(at 0 0 90)
			(size 0.7112 0.7112)
			(layers "B.Cu" "B.Mask" "B.Paste")
			(net "IOC_GPIO_10")
		)
	)
	(footprint ""
		(layer "B.Cu")
		(at 19.144742 -129.077466 180)
		(property "Reference" "R235"
			(at 0 0 0)
			(layer "B.SilkS")
			(hide yes)
			(effects
				(font
					(size 1.27 1.27)
				)
				(justify mirror)
			)
		)
		(property "Value" "120R2F-GP"
			(at -0.064008 -3.993896 180)
			(unlocked yes)
			(layer "B.Fab")
			(hide yes)
			(effects
				(font
					(size 1.016 1.016)
					(thickness 0.1524)
				)
				(justify mirror)
			)
		)
		(property "Device Type" "R402H16"
			(at -0.064008 -5.517896 180)
			(unlocked yes)
			(layer "B.Fab")
			(hide yes)
			(effects
				(font
					(size 1.016 1.016)
					(thickness 0.1524)
				)
				(justify mirror)
			)
		)
		(duplicate_pad_numbers_are_jumpers no)
		(fp_line
			(start 0.508 -0.9398)
			(end 0.508 0.9398)
			(stroke
				(width 0.1524)
				(type default)
			)
			(layer "B.SilkS")
		)
		(fp_line
			(start -0.508 -0.9398)
			(end 0.508 -0.9398)
			(stroke
				(width 0.1524)
				(type default)
			)
			(layer "B.SilkS")
		)
		(fp_rect
			(start 0.508 0.9398)
			(end -0.508 -0.9398)
			(stroke
				(width 0)
				(type default)
			)
			(fill no)
			(layer "B.CrtYd")
		)
		(fp_rect
			(start 0.508 0.9398)
			(end -0.508 -0.9398)
			(stroke
				(width 0)
				(type default)
			)
			(fill no)
			(layer "B.Fab")
		)
		(pad "1" smd custom
			(at 0 -0.4445)
			(size 0.1397 0.1397)
			(layers "B.Cu" "B.Mask" "B.Paste")
			(net "GND")
			(options
				(clearance outline)
				(anchor circle)
			)
			(primitives
				(gr_poly
					(pts
						(arc
							(start -0.1778 0.2794)
							(mid -0.249642 0.249642)
							(end -0.2794 0.1778)
						)
						(arc
							(start -0.2794 -0.1778)
							(mid -0.249642 -0.249642)
							(end -0.1778 -0.2794)
						)
						(arc
							(start 0.1778 -0.2794)
							(mid 0.249642 -0.249642)
							(end 0.2794 -0.1778)
						)
						(arc
							(start 0.2794 0.1778)
							(mid 0.249642 0.249642)
							(end 0.1778 0.2794)
						)
					)
					(width 0)
					(fill yes)
				)
			)
		)
		(pad "2" smd custom
			(at 0 0.4445)
			(size 0.1397 0.1397)
			(layers "B.Cu" "B.Mask" "B.Paste")
			(net "MEMA_1")
			(options
				(clearance outline)
				(anchor circle)
			)
			(primitives
				(gr_poly
					(pts
						(arc
							(start -0.1778 0.2794)
							(mid -0.249642 0.249642)
							(end -0.2794 0.1778)
						)
						(arc
							(start -0.2794 -0.1778)
							(mid -0.249642 -0.249642)
							(end -0.1778 -0.2794)
						)
						(arc
							(start 0.1778 -0.2794)
							(mid 0.249642 -0.249642)
							(end 0.2794 -0.1778)
						)
						(arc
							(start 0.2794 0.1778)
							(mid 0.249642 0.249642)
							(end 0.1778 0.2794)
						)
					)
					(width 0)
					(fill yes)
				)
			)
		)
	)
	(footprint ""
		(layer "B.Cu")
		(at 39.537132 -131.489958 -90)
		(property "Reference" "R611"
			(at 0 0 90)
			(layer "B.SilkS")
			(hide yes)
			(effects
				(font
					(size 1.27 1.27)
				)
				(justify mirror)
			)
		)
		(property "Value" "4K7R2F-GP"
			(at -0.064008 -3.993896 270)
			(unlocked yes)
			(layer "B.Fab")
			(hide yes)
			(effects
				(font
					(size 1.016 1.016)
					(thickness 0.1524)
				)
				(justify mirror)
			)
		)
		(property "Device Type" "R402H16"
			(at -0.064008 -5.517896 270)
			(unlocked yes)
			(layer "B.Fab")
			(hide yes)
			(effects
				(font
					(size 1.016 1.016)
					(thickness 0.1524)
				)
				(justify mirror)
			)
		)
		(duplicate_pad_numbers_are_jumpers no)
		(fp_line
			(start -0.508 -0.9398)
			(end 0.508 -0.9398)
			(stroke
				(width 0.1524)
				(type default)
			)
			(layer "B.SilkS")
		)
		(fp_line
			(start 0.508 -0.9398)
			(end 0.508 0.9398)
			(stroke
				(width 0.1524)
				(type default)
			)
			(layer "B.SilkS")
		)
		(fp_rect
			(start 0.508 0.9398)
			(end -0.508 -0.9398)
			(stroke
				(width 0)
				(type default)
			)
			(fill no)
			(layer "B.CrtYd")
		)
		(fp_rect
			(start 0.508 0.9398)
			(end -0.508 -0.9398)
			(stroke
				(width 0)
				(type default)
			)
			(fill no)
			(layer "B.Fab")
		)
		(pad "1" smd custom
			(at 0 -0.4445 90)
			(size 0.1397 0.1397)
			(layers "B.Cu" "B.Mask" "B.Paste")
			(net "P3V3_STBY")
			(options
				(clearance outline)
				(anchor circle)
			)
			(primitives
				(gr_poly
					(pts
						(arc
							(start -0.1778 0.2794)
							(mid -0.249642 0.249642)
							(end -0.2794 0.1778)
						)
						(arc
							(start -0.2794 -0.1778)
							(mid -0.249642 -0.249642)
							(end -0.1778 -0.2794)
						)
						(arc
							(start 0.1778 -0.2794)
							(mid 0.249642 -0.249642)
							(end 0.2794 -0.1778)
						)
						(arc
							(start 0.2794 0.1778)
							(mid 0.249642 0.249642)
							(end 0.1778 0.2794)
						)
					)
					(width 0)
					(fill yes)
				)
			)
		)
		(pad "2" smd custom
			(at 0 0.4445 90)
			(size 0.1397 0.1397)
			(layers "B.Cu" "B.Mask" "B.Paste")
			(net "BMC_ML_PWR_YELLOW_LED")
			(options
				(clearance outline)
				(anchor circle)
			)
			(primitives
				(gr_poly
					(pts
						(arc
							(start -0.1778 0.2794)
							(mid -0.249642 0.249642)
							(end -0.2794 0.1778)
						)
						(arc
							(start -0.2794 -0.1778)
							(mid -0.249642 -0.249642)
							(end -0.1778 -0.2794)
						)
						(arc
							(start 0.1778 -0.2794)
							(mid 0.249642 -0.249642)
							(end 0.2794 -0.1778)
						)
						(arc
							(start 0.2794 0.1778)
							(mid 0.249642 0.249642)
							(end 0.1778 0.2794)
						)
					)
					(width 0)
					(fill yes)
				)
			)
		)
	)
	(footprint ""
		(layer "B.Cu")
		(at 157.099 -120.142 -90)
		(property "Reference" "C218"
			(at 0 0 90)
			(layer "B.SilkS")
			(hide yes)
			(effects
				(font
					(size 1.27 1.27)
				)
				(justify mirror)
			)
		)
		(property "Value" "SC10U6D3V5KX-4GP"
			(at 0.0762 -6.1214 270)
			(unlocked yes)
			(layer "B.Fab")
			(hide yes)
			(effects
				(font
					(size 1.016 1.016)
					(thickness 0.1524)
				)
				(justify mirror)
			)
		)
		(property "Device Type" "C805H58"
			(at 0.0762 -8.1534 270)
			(unlocked yes)
			(layer "B.Fab")
			(hide yes)
			(effects
				(font
					(size 1.016 1.016)
					(thickness 0.1524)
				)
				(justify mirror)
			)
		)
		(duplicate_pad_numbers_are_jumpers no)
		(fp_line
			(start -0.635 0)
			(end 0.635 0)
			(stroke
				(width 0.508)
				(type default)
			)
			(layer "B.SilkS")
		)
		(fp_rect
			(start 0.9652 1.778)
			(end -0.9652 -1.778)
			(stroke
				(width 0)
				(type default)
			)
			(fill no)
			(layer "B.CrtYd")
		)
		(fp_poly
			(pts
				(xy 0.9652 -1.778) (xy -0.9652 -1.778) (xy -0.9652 1.778) (xy 0.9652 1.778)
			)
			(stroke
				(width 0)
				(type default)
			)
			(fill no)
			(layer "B.Fab")
		)
		(pad "1" smd rect
			(at 0 -0.9652 90)
			(size 1.397 1.143)
			(layers "B.Cu" "B.Mask" "B.Paste")
			(net "P1V8_STBY")
		)
		(pad "2" smd rect
			(at 0 0.9652 90)
			(size 1.397 1.143)
			(layers "B.Cu" "B.Mask" "B.Paste")
			(net "GND")
		)
	)
	(footprint ""
		(layer "B.Cu")
		(at 51.4858 -135.7376)
		(property "Reference" "R167"
			(at 0 0 0)
			(layer "B.SilkS")
			(hide yes)
			(effects
				(font
					(size 1.27 1.27)
				)
				(justify mirror)
			)
		)
		(property "Value" "0R2J-2-GP"
			(at -0.064008 -3.993896 0)
			(unlocked yes)
			(layer "B.Fab")
			(hide yes)
			(effects
				(font
					(size 1.016 1.016)
					(thickness 0.1524)
				)
				(justify mirror)
			)
		)
		(property "Device Type" "R402H16"
			(at -0.064008 -5.517896 0)
			(unlocked yes)
			(layer "B.Fab")
			(hide yes)
			(effects
				(font
					(size 1.016 1.016)
					(thickness 0.1524)
				)
				(justify mirror)
			)
		)
		(duplicate_pad_numbers_are_jumpers no)
		(fp_line
			(start -0.508 -0.9398)
			(end 0.508 -0.9398)
			(stroke
				(width 0.1524)
				(type default)
			)
			(layer "B.SilkS")
		)
		(fp_line
			(start 0.508 -0.9398)
			(end 0.508 0.9398)
			(stroke
				(width 0.1524)
				(type default)
			)
			(layer "B.SilkS")
		)
		(fp_rect
			(start 0.508 0.9398)
			(end -0.508 -0.9398)
			(stroke
				(width 0)
				(type default)
			)
			(fill no)
			(layer "B.CrtYd")
		)
		(fp_rect
			(start 0.508 0.9398)
			(end -0.508 -0.9398)
			(stroke
				(width 0)
				(type default)
			)
			(fill no)
			(layer "B.Fab")
		)
		(pad "1" smd custom
			(at 0 -0.4445 180)
			(size 0.1397 0.1397)
			(layers "B.Cu" "B.Mask" "B.Paste")
			(net "PWRBTN_OUT_N_R")
			(options
				(clearance outline)
				(anchor circle)
			)
			(primitives
				(gr_poly
					(pts
						(arc
							(start -0.1778 0.2794)
							(mid -0.249642 0.249642)
							(end -0.2794 0.1778)
						)
						(arc
							(start -0.2794 -0.1778)
							(mid -0.249642 -0.249642)
							(end -0.1778 -0.2794)
						)
						(arc
							(start 0.1778 -0.2794)
							(mid 0.249642 -0.249642)
							(end 0.2794 -0.1778)
						)
						(arc
							(start 0.2794 0.1778)
							(mid 0.249642 0.249642)
							(end 0.1778 0.2794)
						)
					)
					(width 0)
					(fill yes)
				)
			)
		)
		(pad "2" smd custom
			(at 0 0.4445 180)
			(size 0.1397 0.1397)
			(layers "B.Cu" "B.Mask" "B.Paste")
			(net "PWRBTN_OUT_N")
			(options
				(clearance outline)
				(anchor circle)
			)
			(primitives
				(gr_poly
					(pts
						(arc
							(start -0.1778 0.2794)
							(mid -0.249642 0.249642)
							(end -0.2794 0.1778)
						)
						(arc
							(start -0.2794 -0.1778)
							(mid -0.249642 -0.249642)
							(end -0.1778 -0.2794)
						)
						(arc
							(start 0.1778 -0.2794)
							(mid 0.249642 -0.249642)
							(end 0.2794 -0.1778)
						)
						(arc
							(start 0.2794 0.1778)
							(mid 0.249642 0.249642)
							(end 0.1778 0.2794)
						)
					)
					(width 0)
					(fill yes)
				)
			)
		)
	)
	(footprint ""
		(layer "B.Cu")
		(at 56.847232 -162.025076 90)
		(property "Reference" "R415"
			(at 0 0 90)
			(layer "B.SilkS")
			(hide yes)
			(effects
				(font
					(size 1.27 1.27)
				)
				(justify mirror)
			)
		)
		(property "Value" "1KR2F-3-GP"
			(at -0.064008 -3.993896 90)
			(unlocked yes)
			(layer "B.Fab")
			(hide yes)
			(effects
				(font
					(size 1.016 1.016)
					(thickness 0.1524)
				)
				(justify mirror)
			)
		)
		(property "Device Type" "R402H16"
			(at -0.064008 -5.517896 90)
			(unlocked yes)
			(layer "B.Fab")
			(hide yes)
			(effects
				(font
					(size 1.016 1.016)
					(thickness 0.1524)
				)
				(justify mirror)
			)
		)
		(duplicate_pad_numbers_are_jumpers no)
		(fp_line
			(start 0.508 -0.9398)
			(end 0.508 0.9398)
			(stroke
				(width 0.1524)
				(type default)
			)
			(layer "B.SilkS")
		)
		(fp_line
			(start -0.508 -0.9398)
			(end 0.508 -0.9398)
			(stroke
				(width 0.1524)
				(type default)
			)
			(layer "B.SilkS")
		)
		(fp_rect
			(start 0.508 0.9398)
			(end -0.508 -0.9398)
			(stroke
				(width 0)
				(type default)
			)
			(fill no)
			(layer "B.CrtYd")
		)
		(fp_rect
			(start 0.508 0.9398)
			(end -0.508 -0.9398)
			(stroke
				(width 0)
				(type default)
			)
			(fill no)
			(layer "B.Fab")
		)
		(pad "1" smd custom
			(at 0 -0.4445 270)
			(size 0.1397 0.1397)
			(layers "B.Cu" "B.Mask" "B.Paste")
			(net "ADC_P5V_STBY")
			(options
				(clearance outline)
				(anchor circle)
			)
			(primitives
				(gr_poly
					(pts
						(arc
							(start -0.1778 0.2794)
							(mid -0.249642 0.249642)
							(end -0.2794 0.1778)
						)
						(arc
							(start -0.2794 -0.1778)
							(mid -0.249642 -0.249642)
							(end -0.1778 -0.2794)
						)
						(arc
							(start 0.1778 -0.2794)
							(mid 0.249642 -0.249642)
							(end 0.2794 -0.1778)
						)
						(arc
							(start 0.2794 0.1778)
							(mid 0.249642 0.249642)
							(end 0.1778 0.2794)
						)
					)
					(width 0)
					(fill yes)
				)
			)
		)
		(pad "2" smd custom
			(at 0 0.4445 270)
			(size 0.1397 0.1397)
			(layers "B.Cu" "B.Mask" "B.Paste")
			(net "GND")
			(options
				(clearance outline)
				(anchor circle)
			)
			(primitives
				(gr_poly
					(pts
						(arc
							(start -0.1778 0.2794)
							(mid -0.249642 0.249642)
							(end -0.2794 0.1778)
						)
						(arc
							(start -0.2794 -0.1778)
							(mid -0.249642 -0.249642)
							(end -0.1778 -0.2794)
						)
						(arc
							(start 0.1778 -0.2794)
							(mid 0.249642 -0.249642)
							(end 0.2794 -0.1778)
						)
						(arc
							(start 0.2794 0.1778)
							(mid 0.249642 0.249642)
							(end 0.1778 0.2794)
						)
					)
					(width 0)
					(fill yes)
				)
			)
		)
	)
	(footprint ""
		(layer "B.Cu")
		(at 113.2586 -8.8138)
		(property "Reference" "C150"
			(at 0 0 0)
			(layer "B.SilkS")
			(hide yes)
			(effects
				(font
					(size 1.27 1.27)
				)
				(justify mirror)
			)
		)
		(property "Value" "SCD1U50V3KX-GP"
			(at 0 -2.8194 0)
			(unlocked yes)
			(layer "B.Fab")
			(hide yes)
			(effects
				(font
					(size 1.016 1.016)
					(thickness 0.1524)
				)
				(justify mirror)
			)
		)
		(property "Device Type" "C603H36"
			(at 0 -4.3434 0)
			(unlocked yes)
			(layer "B.Fab")
			(hide yes)
			(effects
				(font
					(size 1.016 1.016)
					(thickness 0.1524)
				)
				(justify mirror)
			)
		)
		(duplicate_pad_numbers_are_jumpers no)
		(fp_line
			(start -0.508 0)
			(end 0.508 0)
			(stroke
				(width 0.2032)
				(type default)
			)
			(layer "B.SilkS")
		)
		(fp_rect
			(start 0.5842 1.3335)
			(end -0.5842 -1.3335)
			(stroke
				(width 0)
				(type default)
			)
			(fill no)
			(layer "B.CrtYd")
		)
		(fp_rect
			(start 0.5842 1.3335)
			(end -0.5842 -1.3335)
			(stroke
				(width 0)
				(type default)
			)
			(fill no)
			(layer "B.Fab")
		)
		(pad "1" smd custom
			(at 0 -0.762 180)
			(size 0.2159 0.2159)
			(layers "B.Cu" "B.Mask" "B.Paste")
			(net "MB0_ISTART_R")
			(options
				(clearance outline)
				(anchor circle)
			)
			(primitives
				(gr_poly
					(pts
						(arc
							(start -0.3302 0.4318)
							(mid -0.402042 0.402042)
							(end -0.4318 0.3302)
						)
						(arc
							(start -0.4318 -0.3302)
							(mid -0.402042 -0.402042)
							(end -0.3302 -0.4318)
						)
						(arc
							(start 0.3302 -0.4318)
							(mid 0.402042 -0.402042)
							(end 0.4318 -0.3302)
						)
						(arc
							(start 0.4318 0.3302)
							(mid 0.402042 0.402042)
							(end 0.3302 0.4318)
						)
					)
					(width 0)
					(fill yes)
				)
			)
		)
		(pad "2" smd custom
			(at 0 0.762 180)
			(size 0.2159 0.2159)
			(layers "B.Cu" "B.Mask" "B.Paste")
			(net "AGND_CURRENT_MON")
			(options
				(clearance outline)
				(anchor circle)
			)
			(primitives
				(gr_poly
					(pts
						(arc
							(start -0.3302 0.4318)
							(mid -0.402042 0.402042)
							(end -0.4318 0.3302)
						)
						(arc
							(start -0.4318 -0.3302)
							(mid -0.402042 -0.402042)
							(end -0.3302 -0.4318)
						)
						(arc
							(start 0.3302 -0.4318)
							(mid 0.402042 -0.402042)
							(end 0.4318 -0.3302)
						)
						(arc
							(start 0.4318 0.3302)
							(mid 0.402042 0.402042)
							(end 0.3302 0.4318)
						)
					)
					(width 0)
					(fill yes)
				)
			)
		)
	)
	(footprint ""
		(layer "B.Cu")
		(at 57.404 -148.8186 -90)
		(property "Reference" "R359"
			(at 0 0 90)
			(layer "B.SilkS")
			(hide yes)
			(effects
				(font
					(size 1.27 1.27)
				)
				(justify mirror)
			)
		)
		(property "Value" "10KR2F-2-GP"
			(at -0.064008 -3.993896 270)
			(unlocked yes)
			(layer "B.Fab")
			(hide yes)
			(effects
				(font
					(size 1.016 1.016)
					(thickness 0.1524)
				)
				(justify mirror)
			)
		)
		(property "Device Type" "R402H16"
			(at -0.064008 -5.517896 270)
			(unlocked yes)
			(layer "B.Fab")
			(hide yes)
			(effects
				(font
					(size 1.016 1.016)
					(thickness 0.1524)
				)
				(justify mirror)
			)
		)
		(duplicate_pad_numbers_are_jumpers no)
		(fp_line
			(start -0.508 -0.9398)
			(end 0.508 -0.9398)
			(stroke
				(width 0.1524)
				(type default)
			)
			(layer "B.SilkS")
		)
		(fp_line
			(start 0.508 -0.9398)
			(end 0.508 0.9398)
			(stroke
				(width 0.1524)
				(type default)
			)
			(layer "B.SilkS")
		)
		(fp_rect
			(start 0.508 0.9398)
			(end -0.508 -0.9398)
			(stroke
				(width 0)
				(type default)
			)
			(fill no)
			(layer "B.CrtYd")
		)
		(fp_rect
			(start 0.508 0.9398)
			(end -0.508 -0.9398)
			(stroke
				(width 0)
				(type default)
			)
			(fill no)
			(layer "B.Fab")
		)
		(pad "1" smd custom
			(at 0 -0.4445 90)
			(size 0.1397 0.1397)
			(layers "B.Cu" "B.Mask" "B.Paste")
			(net "P3V3_STBY")
			(options
				(clearance outline)
				(anchor circle)
			)
			(primitives
				(gr_poly
					(pts
						(arc
							(start -0.1778 0.2794)
							(mid -0.249642 0.249642)
							(end -0.2794 0.1778)
						)
						(arc
							(start -0.2794 -0.1778)
							(mid -0.249642 -0.249642)
							(end -0.1778 -0.2794)
						)
						(arc
							(start 0.1778 -0.2794)
							(mid 0.249642 -0.249642)
							(end 0.2794 -0.1778)
						)
						(arc
							(start 0.2794 0.1778)
							(mid 0.249642 0.249642)
							(end 0.1778 0.2794)
						)
					)
					(width 0)
					(fill yes)
				)
			)
		)
		(pad "2" smd custom
			(at 0 0.4445 90)
			(size 0.1397 0.1397)
			(layers "B.Cu" "B.Mask" "B.Paste")
			(net "JTAG_BMC_TMS")
			(options
				(clearance outline)
				(anchor circle)
			)
			(primitives
				(gr_poly
					(pts
						(arc
							(start -0.1778 0.2794)
							(mid -0.249642 0.249642)
							(end -0.2794 0.1778)
						)
						(arc
							(start -0.2794 -0.1778)
							(mid -0.249642 -0.249642)
							(end -0.1778 -0.2794)
						)
						(arc
							(start 0.1778 -0.2794)
							(mid 0.249642 -0.249642)
							(end 0.2794 -0.1778)
						)
						(arc
							(start 0.2794 0.1778)
							(mid 0.249642 0.249642)
							(end 0.1778 0.2794)
						)
					)
					(width 0)
					(fill yes)
				)
			)
		)
	)
)
